(kicad_pcb
	(version 20260206)
	(generator "pcbnew")
	(generator_version "10.0")
	(general
		(thickness 1.6)
		(legacy_teardrops no)
	)
	(paper "A4")
	(title_block
		(title "04192023_DAF0TMB3IC0_F0TG_MB_C_brd_V02_OCP.brd")
		(comment 1 "Grand Teton / footprints 5699-5705 of 8354")
	)
	(layers
		(0 "F.Cu" signal "TOP")
		(4 "In1.Cu" signal "GND")
		(6 "In2.Cu" signal "IN1")
		(8 "In3.Cu" signal "GND1")
		(10 "In4.Cu" signal "IN2")
		(12 "In5.Cu" signal "GND2")
		(14 "In6.Cu" signal "IN3")
		(16 "In7.Cu" signal "GND3")
		(18 "In8.Cu" signal "VCC")
		(20 "In9.Cu" signal "VCC1")
		(22 "In10.Cu" signal "GND4")
		(24 "In11.Cu" signal "IN4")
		(26 "In12.Cu" signal "GND5")
		(28 "In13.Cu" signal "IN5")
		(30 "In14.Cu" signal "GND6")
		(32 "In15.Cu" signal "IN6")
		(34 "In16.Cu" signal "GND7")
		(2 "B.Cu" signal "BOTTOM")
		(9 "F.Adhes" user "F.Adhesive")
		(11 "B.Adhes" user "B.Adhesive")
		(13 "F.Paste" user "Package Geometry/Pastemask Top")
		(15 "B.Paste" user "Package Geometry/Pastemask Bottom")
		(5 "F.SilkS" user "Ref Des/Silkscreen Top")
		(7 "B.SilkS" user "Ref Des/Silkscreen Bottom")
		(1 "F.Mask" user "Board Geometry/Soldermask Top")
		(3 "B.Mask" user "Board Geometry/Soldermask Bottom")
		(17 "Dwgs.User" user "User.Drawings")
		(19 "Cmts.User" user "User.Comments")
		(21 "Eco1.User" user "User.Eco1")
		(23 "Eco2.User" user "User.Eco2")
		(25 "Edge.Cuts" user "Board Geometry/Outline")
		(27 "Margin" user)
		(31 "F.CrtYd" user "Package Geometry/Place Bound Top")
		(29 "B.CrtYd" user "Package Geometry/Place Bound Bottom")
		(35 "F.Fab" user "Ref Des/Assembly Top")
		(33 "B.Fab" user "Ref Des/Assembly Bottom")
	)
	(footprint ""
		(layer "B.Cu")
		(at 110.856014 -257.74523 180)
		(property "Reference" "C2433"
			(at 0 0 0)
			(layer "B.SilkS")
			(hide yes)
			(effects
				(font
					(size 1.27 1.27)
				)
				(justify mirror)
			)
		)
		(property "Value" ""
			(at 0 0 0)
			(layer "B.Fab")
			(effects
				(font
					(size 1.27 1.27)
				)
				(justify mirror)
			)
		)
		(duplicate_pad_numbers_are_jumpers no)
		(fp_line
			(start 0.7874 0.4064)
			(end 0.7874 -0.4064)
			(stroke
				(width 0.1524)
				(type default)
			)
			(layer "B.SilkS")
		)
		(fp_line
			(start 0.7874 -0.4064)
			(end -0.7874 -0.4064)
			(stroke
				(width 0.1524)
				(type default)
			)
			(layer "B.SilkS")
		)
		(fp_line
			(start -0.7874 0.4064)
			(end 0.7874 0.4064)
			(stroke
				(width 0.1524)
				(type default)
			)
			(layer "B.SilkS")
		)
		(fp_line
			(start -0.7874 -0.4064)
			(end -0.7874 0.4064)
			(stroke
				(width 0.1524)
				(type default)
			)
			(layer "B.SilkS")
		)
		(fp_line
			(start 0.67945 0.3048)
			(end 0.67945 -0.305054)
			(stroke
				(width 0.1)
				(type default)
			)
			(layer "B.Fab")
		)
		(fp_line
			(start 0.67945 -0.305054)
			(end 0.12065 -0.305054)
			(stroke
				(width 0.1)
				(type default)
			)
			(layer "B.Fab")
		)
		(fp_line
			(start 0.12065 0.3048)
			(end 0.67945 0.3048)
			(stroke
				(width 0.1)
				(type default)
			)
			(layer "B.Fab")
		)
		(fp_line
			(start 0.12065 0.2794)
			(end 0.12065 0.3048)
			(stroke
				(width 0.1)
				(type default)
			)
			(layer "B.Fab")
		)
		(fp_line
			(start 0.12065 -0.2794)
			(end -0.12065 -0.2794)
			(stroke
				(width 0.1)
				(type default)
			)
			(layer "B.Fab")
		)
		(fp_line
			(start 0.12065 -0.305054)
			(end 0.12065 -0.2794)
			(stroke
				(width 0.1)
				(type default)
			)
			(layer "B.Fab")
		)
		(fp_line
			(start -0.120396 0.3048)
			(end -0.120396 0.2794)
			(stroke
				(width 0.1)
				(type default)
			)
			(layer "B.Fab")
		)
		(fp_line
			(start -0.120396 0.2794)
			(end 0.12065 0.2794)
			(stroke
				(width 0.1)
				(type default)
			)
			(layer "B.Fab")
		)
		(fp_line
			(start -0.12065 -0.2794)
			(end -0.12065 -0.3048)
			(stroke
				(width 0.1)
				(type default)
			)
			(layer "B.Fab")
		)
		(fp_line
			(start -0.12065 -0.3048)
			(end -0.67945 -0.3048)
			(stroke
				(width 0.1)
				(type default)
			)
			(layer "B.Fab")
		)
		(fp_line
			(start -0.67945 0.3048)
			(end -0.120396 0.3048)
			(stroke
				(width 0.1)
				(type default)
			)
			(layer "B.Fab")
		)
		(fp_line
			(start -0.67945 -0.3048)
			(end -0.67945 0.3048)
			(stroke
				(width 0.1)
				(type default)
			)
			(layer "B.Fab")
		)
		(pad "1" smd circle
			(at 0.40005 0)
			(size 0 0)
			(layers "B.Cu" "B.Mask" "B.Paste")
			(net "PVDDCR_SOC_P1")
		)
		(pad "2" smd circle
			(at -0.40005 0)
			(size 0 0)
			(layers "B.Cu" "B.Mask" "B.Paste")
			(net "GND")
		)
	)
	(footprint ""
		(layer "B.Cu")
		(at 195.359782 -193.996564)
		(property "Reference" "R114"
			(at 0 0 0)
			(layer "B.SilkS")
			(hide yes)
			(effects
				(font
					(size 1.27 1.27)
				)
				(justify mirror)
			)
		)
		(property "Value" ""
			(at 0 0 0)
			(layer "B.Fab")
			(effects
				(font
					(size 1.27 1.27)
				)
				(justify mirror)
			)
		)
		(duplicate_pad_numbers_are_jumpers no)
		(fp_line
			(start -0.7874 -0.4064)
			(end -0.7874 0.4064)
			(stroke
				(width 0.1524)
				(type default)
			)
			(layer "B.SilkS")
		)
		(fp_line
			(start -0.7874 0.4064)
			(end 0.7874 0.4064)
			(stroke
				(width 0.1524)
				(type default)
			)
			(layer "B.SilkS")
		)
		(fp_line
			(start 0.7874 -0.4064)
			(end -0.7874 -0.4064)
			(stroke
				(width 0.1524)
				(type default)
			)
			(layer "B.SilkS")
		)
		(fp_line
			(start 0.7874 0.4064)
			(end 0.7874 -0.4064)
			(stroke
				(width 0.1524)
				(type default)
			)
			(layer "B.SilkS")
		)
		(fp_line
			(start -0.67945 -0.3048)
			(end -0.67945 0.3048)
			(stroke
				(width 0.1)
				(type default)
			)
			(layer "B.Fab")
		)
		(fp_line
			(start -0.67945 0.3048)
			(end -0.120396 0.3048)
			(stroke
				(width 0.1)
				(type default)
			)
			(layer "B.Fab")
		)
		(fp_line
			(start -0.12065 -0.3048)
			(end -0.67945 -0.3048)
			(stroke
				(width 0.1)
				(type default)
			)
			(layer "B.Fab")
		)
		(fp_line
			(start -0.12065 -0.2794)
			(end -0.12065 -0.3048)
			(stroke
				(width 0.1)
				(type default)
			)
			(layer "B.Fab")
		)
		(fp_line
			(start -0.120396 0.2794)
			(end 0.12065 0.2794)
			(stroke
				(width 0.1)
				(type default)
			)
			(layer "B.Fab")
		)
		(fp_line
			(start -0.120396 0.3048)
			(end -0.120396 0.2794)
			(stroke
				(width 0.1)
				(type default)
			)
			(layer "B.Fab")
		)
		(fp_line
			(start 0.12065 -0.305054)
			(end 0.12065 -0.2794)
			(stroke
				(width 0.1)
				(type default)
			)
			(layer "B.Fab")
		)
		(fp_line
			(start 0.12065 -0.2794)
			(end -0.12065 -0.2794)
			(stroke
				(width 0.1)
				(type default)
			)
			(layer "B.Fab")
		)
		(fp_line
			(start 0.12065 0.2794)
			(end 0.12065 0.3048)
			(stroke
				(width 0.1)
				(type default)
			)
			(layer "B.Fab")
		)
		(fp_line
			(start 0.12065 0.3048)
			(end 0.67945 0.3048)
			(stroke
				(width 0.1)
				(type default)
			)
			(layer "B.Fab")
		)
		(fp_line
			(start 0.67945 -0.305054)
			(end 0.12065 -0.305054)
			(stroke
				(width 0.1)
				(type default)
			)
			(layer "B.Fab")
		)
		(fp_line
			(start 0.67945 0.3048)
			(end 0.67945 -0.305054)
			(stroke
				(width 0.1)
				(type default)
			)
			(layer "B.Fab")
		)
		(pad "1" smd circle
			(at 0.40005 0 180)
			(size 0 0)
			(layers "B.Cu" "B.Mask" "B.Paste")
			(net "P3V3")
		)
		(pad "2" smd circle
			(at -0.40005 0 180)
			(size 0 0)
			(layers "B.Cu" "B.Mask" "B.Paste")
			(net "PWRGD_CHK_CPU1_DIMM")
		)
	)
	(footprint ""
		(layer "B.Cu")
		(at 365.836454 -249.36831)
		(property "Reference" "C10179"
			(at 0 0 0)
			(layer "B.SilkS")
			(hide yes)
			(effects
				(font
					(size 1.27 1.27)
				)
				(justify mirror)
			)
		)
		(property "Value" ""
			(at 0 0 0)
			(layer "B.Fab")
			(effects
				(font
					(size 1.27 1.27)
				)
				(justify mirror)
			)
		)
		(duplicate_pad_numbers_are_jumpers no)
		(fp_line
			(start -0.7874 -0.4064)
			(end -0.7874 0.4064)
			(stroke
				(width 0.1524)
				(type default)
			)
			(layer "B.SilkS")
		)
		(fp_line
			(start -0.7874 0.4064)
			(end 0.7874 0.4064)
			(stroke
				(width 0.1524)
				(type default)
			)
			(layer "B.SilkS")
		)
		(fp_line
			(start 0.7874 -0.4064)
			(end -0.7874 -0.4064)
			(stroke
				(width 0.1524)
				(type default)
			)
			(layer "B.SilkS")
		)
		(fp_line
			(start 0.7874 0.4064)
			(end 0.7874 -0.4064)
			(stroke
				(width 0.1524)
				(type default)
			)
			(layer "B.SilkS")
		)
		(fp_line
			(start -0.67945 -0.3048)
			(end -0.67945 0.3048)
			(stroke
				(width 0.1)
				(type default)
			)
			(layer "B.Fab")
		)
		(fp_line
			(start -0.67945 0.3048)
			(end -0.120396 0.3048)
			(stroke
				(width 0.1)
				(type default)
			)
			(layer "B.Fab")
		)
		(fp_line
			(start -0.12065 -0.3048)
			(end -0.67945 -0.3048)
			(stroke
				(width 0.1)
				(type default)
			)
			(layer "B.Fab")
		)
		(fp_line
			(start -0.12065 -0.2794)
			(end -0.12065 -0.3048)
			(stroke
				(width 0.1)
				(type default)
			)
			(layer "B.Fab")
		)
		(fp_line
			(start -0.120396 0.2794)
			(end 0.12065 0.2794)
			(stroke
				(width 0.1)
				(type default)
			)
			(layer "B.Fab")
		)
		(fp_line
			(start -0.120396 0.3048)
			(end -0.120396 0.2794)
			(stroke
				(width 0.1)
				(type default)
			)
			(layer "B.Fab")
		)
		(fp_line
			(start 0.12065 -0.305054)
			(end 0.12065 -0.2794)
			(stroke
				(width 0.1)
				(type default)
			)
			(layer "B.Fab")
		)
		(fp_line
			(start 0.12065 -0.2794)
			(end -0.12065 -0.2794)
			(stroke
				(width 0.1)
				(type default)
			)
			(layer "B.Fab")
		)
		(fp_line
			(start 0.12065 0.2794)
			(end 0.12065 0.3048)
			(stroke
				(width 0.1)
				(type default)
			)
			(layer "B.Fab")
		)
		(fp_line
			(start 0.12065 0.3048)
			(end 0.67945 0.3048)
			(stroke
				(width 0.1)
				(type default)
			)
			(layer "B.Fab")
		)
		(fp_line
			(start 0.67945 -0.305054)
			(end 0.12065 -0.305054)
			(stroke
				(width 0.1)
				(type default)
			)
			(layer "B.Fab")
		)
		(fp_line
			(start 0.67945 0.3048)
			(end 0.67945 -0.305054)
			(stroke
				(width 0.1)
				(type default)
			)
			(layer "B.Fab")
		)
		(pad "1" smd circle
			(at 0.40005 0 180)
			(size 0 0)
			(layers "B.Cu" "B.Mask" "B.Paste")
			(net "PVDDCR_CPU0_P0")
		)
		(pad "2" smd circle
			(at -0.40005 0 180)
			(size 0 0)
			(layers "B.Cu" "B.Mask" "B.Paste")
			(net "GND")
		)
	)
	(footprint ""
		(layer "B.Cu")
		(at 138.24204 -389.43026)
		(property "Reference" "PJ09_P1_N"
			(at 0 0 0)
			(layer "B.SilkS")
			(hide yes)
			(effects
				(font
					(size 1.27 1.27)
				)
				(justify mirror)
			)
		)
		(property "Value" ""
			(at 0 0 0)
			(layer "B.Fab")
			(effects
				(font
					(size 1.27 1.27)
				)
				(justify mirror)
			)
		)
		(duplicate_pad_numbers_are_jumpers no)
		(zone
			(layer "In15.Cu")
			(hatch none 0.5)
			(connect_pads
				(clearance 0)
			)
			(min_thickness 0.25)
			(keepout
				(tracks allowed)
				(vias not_allowed)
				(pads allowed)
				(copperpour not_allowed)
				(footprints allowed)
			)
			(placement
				(enabled no)
				(sheetname "")
			)
			(fill
				(thermal_gap 0.5)
				(thermal_bridge_width 0.5)
				(island_removal_mode 0)
			)
			(polygon
				(pts
					(xy 138.45794 -389.23976) (xy 138.02614 -389.23976) (xy 138.02614 -389.62076) (xy 138.45794 -389.62076)
				)
			)
		)
	)
	(footprint ""
		(layer "B.Cu")
		(at 128.505204 -35.686492 180)
		(property "Reference" "C6054"
			(at 0 0 0)
			(layer "B.SilkS")
			(hide yes)
			(effects
				(font
					(size 1.27 1.27)
				)
				(justify mirror)
			)
		)
		(property "Value" ""
			(at 0 0 0)
			(layer "B.Fab")
			(effects
				(font
					(size 1.27 1.27)
				)
				(justify mirror)
			)
		)
		(duplicate_pad_numbers_are_jumpers no)
		(fp_line
			(start 0.7874 0.4064)
			(end 0.7874 -0.4064)
			(stroke
				(width 0.1524)
				(type default)
			)
			(layer "B.SilkS")
		)
		(fp_line
			(start 0.7874 -0.4064)
			(end -0.7874 -0.4064)
			(stroke
				(width 0.1524)
				(type default)
			)
			(layer "B.SilkS")
		)
		(fp_line
			(start -0.7874 0.4064)
			(end 0.7874 0.4064)
			(stroke
				(width 0.1524)
				(type default)
			)
			(layer "B.SilkS")
		)
		(fp_line
			(start -0.7874 -0.4064)
			(end -0.7874 0.4064)
			(stroke
				(width 0.1524)
				(type default)
			)
			(layer "B.SilkS")
		)
		(fp_line
			(start 0.67945 0.3048)
			(end 0.67945 -0.305054)
			(stroke
				(width 0.1)
				(type default)
			)
			(layer "B.Fab")
		)
		(fp_line
			(start 0.67945 -0.305054)
			(end 0.12065 -0.305054)
			(stroke
				(width 0.1)
				(type default)
			)
			(layer "B.Fab")
		)
		(fp_line
			(start 0.12065 0.3048)
			(end 0.67945 0.3048)
			(stroke
				(width 0.1)
				(type default)
			)
			(layer "B.Fab")
		)
		(fp_line
			(start 0.12065 0.2794)
			(end 0.12065 0.3048)
			(stroke
				(width 0.1)
				(type default)
			)
			(layer "B.Fab")
		)
		(fp_line
			(start 0.12065 -0.2794)
			(end -0.12065 -0.2794)
			(stroke
				(width 0.1)
				(type default)
			)
			(layer "B.Fab")
		)
		(fp_line
			(start 0.12065 -0.305054)
			(end 0.12065 -0.2794)
			(stroke
				(width 0.1)
				(type default)
			)
			(layer "B.Fab")
		)
		(fp_line
			(start -0.120396 0.3048)
			(end -0.120396 0.2794)
			(stroke
				(width 0.1)
				(type default)
			)
			(layer "B.Fab")
		)
		(fp_line
			(start -0.120396 0.2794)
			(end 0.12065 0.2794)
			(stroke
				(width 0.1)
				(type default)
			)
			(layer "B.Fab")
		)
		(fp_line
			(start -0.12065 -0.2794)
			(end -0.12065 -0.3048)
			(stroke
				(width 0.1)
				(type default)
			)
			(layer "B.Fab")
		)
		(fp_line
			(start -0.12065 -0.3048)
			(end -0.67945 -0.3048)
			(stroke
				(width 0.1)
				(type default)
			)
			(layer "B.Fab")
		)
		(fp_line
			(start -0.67945 0.3048)
			(end -0.120396 0.3048)
			(stroke
				(width 0.1)
				(type default)
			)
			(layer "B.Fab")
		)
		(fp_line
			(start -0.67945 -0.3048)
			(end -0.67945 0.3048)
			(stroke
				(width 0.1)
				(type default)
			)
			(layer "B.Fab")
		)
		(pad "1" smd circle
			(at 0.40005 0)
			(size 0 0)
			(layers "B.Cu" "B.Mask" "B.Paste")
			(net "P1V2_AUX")
		)
		(pad "2" smd circle
			(at -0.40005 0)
			(size 0 0)
			(layers "B.Cu" "B.Mask" "B.Paste")
			(net "GND")
		)
	)
	(footprint ""
		(layer "B.Cu")
		(at 72.825864 -11.26871 90)
		(property "Reference" "R3163"
			(at 0 0 90)
			(layer "B.SilkS")
			(hide yes)
			(effects
				(font
					(size 1.27 1.27)
				)
				(justify mirror)
			)
		)
		(property "Value" ""
			(at 0 0 90)
			(layer "B.Fab")
			(effects
				(font
					(size 1.27 1.27)
				)
				(justify mirror)
			)
		)
		(duplicate_pad_numbers_are_jumpers no)
		(fp_line
			(start 0.7874 -0.4064)
			(end -0.7874 -0.4064)
			(stroke
				(width 0.1524)
				(type default)
			)
			(layer "B.SilkS")
		)
		(fp_line
			(start -0.7874 -0.4064)
			(end -0.7874 0.4064)
			(stroke
				(width 0.1524)
				(type default)
			)
			(layer "B.SilkS")
		)
		(fp_line
			(start 0.7874 0.4064)
			(end 0.7874 -0.4064)
			(stroke
				(width 0.1524)
				(type default)
			)
			(layer "B.SilkS")
		)
		(fp_line
			(start -0.7874 0.4064)
			(end 0.7874 0.4064)
			(stroke
				(width 0.1524)
				(type default)
			)
			(layer "B.SilkS")
		)
		(fp_line
			(start 0.67945 -0.305054)
			(end 0.12065 -0.305054)
			(stroke
				(width 0.1)
				(type default)
			)
			(layer "B.Fab")
		)
		(fp_line
			(start 0.12065 -0.305054)
			(end 0.12065 -0.2794)
			(stroke
				(width 0.1)
				(type default)
			)
			(layer "B.Fab")
		)
		(fp_line
			(start -0.12065 -0.3048)
			(end -0.67945 -0.3048)
			(stroke
				(width 0.1)
				(type default)
			)
			(layer "B.Fab")
		)
		(fp_line
			(start -0.67945 -0.3048)
			(end -0.67945 0.3048)
			(stroke
				(width 0.1)
				(type default)
			)
			(layer "B.Fab")
		)
		(fp_line
			(start 0.12065 -0.2794)
			(end -0.12065 -0.2794)
			(stroke
				(width 0.1)
				(type default)
			)
			(layer "B.Fab")
		)
		(fp_line
			(start -0.12065 -0.2794)
			(end -0.12065 -0.3048)
			(stroke
				(width 0.1)
				(type default)
			)
			(layer "B.Fab")
		)
		(fp_line
			(start 0.12065 0.2794)
			(end 0.12065 0.3048)
			(stroke
				(width 0.1)
				(type default)
			)
			(layer "B.Fab")
		)
		(fp_line
			(start -0.120396 0.2794)
			(end 0.12065 0.2794)
			(stroke
				(width 0.1)
				(type default)
			)
			(layer "B.Fab")
		)
		(fp_line
			(start 0.67945 0.3048)
			(end 0.67945 -0.305054)
			(stroke
				(width 0.1)
				(type default)
			)
			(layer "B.Fab")
		)
		(fp_line
			(start 0.12065 0.3048)
			(end 0.67945 0.3048)
			(stroke
				(width 0.1)
				(type default)
			)
			(layer "B.Fab")
		)
		(fp_line
			(start -0.120396 0.3048)
			(end -0.120396 0.2794)
			(stroke
				(width 0.1)
				(type default)
			)
			(layer "B.Fab")
		)
		(fp_line
			(start -0.67945 0.3048)
			(end -0.120396 0.3048)
			(stroke
				(width 0.1)
				(type default)
			)
			(layer "B.Fab")
		)
		(pad "1" smd circle
			(at 0.40005 0 270)
			(size 0 0)
			(layers "B.Cu" "B.Mask" "B.Paste")
			(net "OCP_V3_2_ID0")
		)
		(pad "2" smd circle
			(at -0.40005 0 270)
			(size 0 0)
			(layers "B.Cu" "B.Mask" "B.Paste")
			(net "GND")
		)
	)
	(footprint ""
		(layer "B.Cu")
		(at 348.418912 -257.930142 180)
		(property "Reference" "C2643"
			(at 0 0 0)
			(layer "B.SilkS")
			(hide yes)
			(effects
				(font
					(size 1.27 1.27)
				)
				(justify mirror)
			)
		)
		(property "Value" ""
			(at 0 0 0)
			(layer "B.Fab")
			(effects
				(font
					(size 1.27 1.27)
				)
				(justify mirror)
			)
		)
		(duplicate_pad_numbers_are_jumpers no)
		(fp_line
			(start 0.7874 0.4064)
			(end 0.7874 -0.4064)
			(stroke
				(width 0.1524)
				(type default)
			)
			(layer "B.SilkS")
		)
		(fp_line
			(start 0.7874 -0.4064)
			(end -0.7874 -0.4064)
			(stroke
				(width 0.1524)
				(type default)
			)
			(layer "B.SilkS")
		)
		(fp_line
			(start -0.7874 0.4064)
			(end 0.7874 0.4064)
			(stroke
				(width 0.1524)
				(type default)
			)
			(layer "B.SilkS")
		)
		(fp_line
			(start -0.7874 -0.4064)
			(end -0.7874 0.4064)
			(stroke
				(width 0.1524)
				(type default)
			)
			(layer "B.SilkS")
		)
		(fp_line
			(start 0.67945 0.3048)
			(end 0.67945 -0.305054)
			(stroke
				(width 0.1)
				(type default)
			)
			(layer "B.Fab")
		)
		(fp_line
			(start 0.67945 -0.305054)
			(end 0.12065 -0.305054)
			(stroke
				(width 0.1)
				(type default)
			)
			(layer "B.Fab")
		)
		(fp_line
			(start 0.12065 0.3048)
			(end 0.67945 0.3048)
			(stroke
				(width 0.1)
				(type default)
			)
			(layer "B.Fab")
		)
		(fp_line
			(start 0.12065 0.2794)
			(end 0.12065 0.3048)
			(stroke
				(width 0.1)
				(type default)
			)
			(layer "B.Fab")
		)
		(fp_line
			(start 0.12065 -0.2794)
			(end -0.12065 -0.2794)
			(stroke
				(width 0.1)
				(type default)
			)
			(layer "B.Fab")
		)
		(fp_line
			(start 0.12065 -0.305054)
			(end 0.12065 -0.2794)
			(stroke
				(width 0.1)
				(type default)
			)
			(layer "B.Fab")
		)
		(fp_line
			(start -0.120396 0.3048)
			(end -0.120396 0.2794)
			(stroke
				(width 0.1)
				(type default)
			)
			(layer "B.Fab")
		)
		(fp_line
			(start -0.120396 0.2794)
			(end 0.12065 0.2794)
			(stroke
				(width 0.1)
				(type default)
			)
			(layer "B.Fab")
		)
		(fp_line
			(start -0.12065 -0.2794)
			(end -0.12065 -0.3048)
			(stroke
				(width 0.1)
				(type default)
			)
			(layer "B.Fab")
		)
		(fp_line
			(start -0.12065 -0.3048)
			(end -0.67945 -0.3048)
			(stroke
				(width 0.1)
				(type default)
			)
			(layer "B.Fab")
		)
		(fp_line
			(start -0.67945 0.3048)
			(end -0.120396 0.3048)
			(stroke
				(width 0.1)
				(type default)
			)
			(layer "B.Fab")
		)
		(fp_line
			(start -0.67945 -0.3048)
			(end -0.67945 0.3048)
			(stroke
				(width 0.1)
				(type default)
			)
			(layer "B.Fab")
		)
		(pad "1" smd circle
			(at 0.40005 0)
			(size 0 0)
			(layers "B.Cu" "B.Mask" "B.Paste")
			(net "PVDDIO_P0")
		)
		(pad "2" smd circle
			(at -0.40005 0)
			(size 0 0)
			(layers "B.Cu" "B.Mask" "B.Paste")
			(net "GND")
		)
	)
)
